# S9S_MB_2U (Grand Teton) — schematic netlist excerpt (pin names and nets, part order shuffled) for the footprints in the layout excerpt that follows; sources: Cadence DE-HDL packaged netlist, KiCad conversion of 03242023_DA0F0TMBIJ0_F0T_Motherboard_J_brd_V01_OCP.brd

R4194  Q_RES  1K 1% EMPTY  pkg 0402LF  page 170 : A = P3V3_AUX ; B = U272_2_ADD1
C2386  Q_CAP  100NF 50V 10% EMPTY  pkg C0402  page 307 : A = PWRGD_DSW_PWROK_TRIGGER ; B = GND

(kicad_pcb
	(version 20260206)
	(generator "pcbnew")
	(generator_version "10.0")
	(general
		(thickness 1.6)
		(legacy_teardrops no)
	)
	(paper "A4")
	(title_block
		(title "03242023_DA0F0TMBIJ0_F0T_Motherboard_J_brd_V01_OCP.brd")
		(comment 1 "Grand Teton / footprints 3369-3370 of 6105")
	)
	(layers
		(0 "F.Cu" signal "TOP")
		(4 "In1.Cu" signal "GND")
		(6 "In2.Cu" signal "IN1")
		(8 "In3.Cu" signal "GND1")
		(10 "In4.Cu" signal "IN2")
		(12 "In5.Cu" signal "GND2")
		(14 "In6.Cu" signal "IN3")
		(16 "In7.Cu" signal "GND3")
		(18 "In8.Cu" signal "VCC")
		(20 "In9.Cu" signal "VCC1")
		(22 "In10.Cu" signal "GND4")
		(24 "In11.Cu" signal "IN4")
		(26 "In12.Cu" signal "GND5")
		(28 "In13.Cu" signal "IN5")
		(30 "In14.Cu" signal "GND6")
		(32 "In15.Cu" signal "IN6")
		(34 "In16.Cu" signal "GND7")
		(2 "B.Cu" signal "BOTTOM")
		(9 "F.Adhes" user "F.Adhesive")
		(11 "B.Adhes" user "B.Adhesive")
		(13 "F.Paste" user "Package Geometry/Pastemask Top")
		(15 "B.Paste" user "Package Geometry/Pastemask Bottom")
		(5 "F.SilkS" user "Ref Des/Silkscreen Top")
		(7 "B.SilkS" user "Ref Des/Silkscreen Bottom")
		(1 "F.Mask" user "Board Geometry/Soldermask Top")
		(3 "B.Mask" user "Board Geometry/Soldermask Bottom")
		(17 "Dwgs.User" user "User.Drawings")
		(19 "Cmts.User" user "User.Comments")
		(21 "Eco1.User" user "User.Eco1")
		(23 "Eco2.User" user "User.Eco2")
		(25 "Edge.Cuts" user "Board Geometry/Outline")
		(27 "Margin" user)
		(31 "F.CrtYd" user "Package Geometry/Place Bound Top")
		(29 "B.CrtYd" user "Package Geometry/Place Bound Bottom")
		(35 "F.Fab" user "Ref Des/Assembly Top")
		(33 "B.Fab" user "Ref Des/Assembly Bottom")
	)
	(footprint ""
		(layer "F.Cu")
		(at 97.821242 -417.766246 90)
		(property "Reference" "R4194"
			(at 0 0 90)
			(layer "F.SilkS")
			(hide yes)
			(effects
				(font
					(size 1.27 1.27)
				)
			)
		)
		(property "Value" ""
			(at 0 0 90)
			(layer "F.Fab")
			(effects
				(font
					(size 1.27 1.27)
				)
			)
		)
		(duplicate_pad_numbers_are_jumpers no)
		(fp_line
			(start 0.7874 -0.4064)
			(end 0.7874 0.4064)
			(stroke
				(width 0.1524)
				(type default)
			)
			(layer "F.SilkS")
		)
		(fp_line
			(start -0.7874 -0.4064)
			(end 0.7874 -0.4064)
			(stroke
				(width 0.1524)
				(type default)
			)
			(layer "F.SilkS")
		)
		(fp_line
			(start 0.7874 0.4064)
			(end -0.7874 0.4064)
			(stroke
				(width 0.1524)
				(type default)
			)
			(layer "F.SilkS")
		)
		(fp_line
			(start -0.7874 0.4064)
			(end -0.7874 -0.4064)
			(stroke
				(width 0.1524)
				(type default)
			)
			(layer "F.SilkS")
		)
		(fp_line
			(start -0.12065 -0.305054)
			(end -0.12065 -0.2794)
			(stroke
				(width 0.1)
				(type default)
			)
			(layer "F.Fab")
		)
		(fp_line
			(start -0.67945 -0.305054)
			(end -0.12065 -0.305054)
			(stroke
				(width 0.1)
				(type default)
			)
			(layer "F.Fab")
		)
		(fp_line
			(start 0.67945 -0.3048)
			(end 0.67945 0.3048)
			(stroke
				(width 0.1)
				(type default)
			)
			(layer "F.Fab")
		)
		(fp_line
			(start 0.12065 -0.3048)
			(end 0.67945 -0.3048)
			(stroke
				(width 0.1)
				(type default)
			)
			(layer "F.Fab")
		)
		(fp_line
			(start 0.12065 -0.2794)
			(end 0.12065 -0.3048)
			(stroke
				(width 0.1)
				(type default)
			)
			(layer "F.Fab")
		)
		(fp_line
			(start -0.12065 -0.2794)
			(end 0.12065 -0.2794)
			(stroke
				(width 0.1)
				(type default)
			)
			(layer "F.Fab")
		)
		(fp_line
			(start 0.120396 0.2794)
			(end -0.12065 0.2794)
			(stroke
				(width 0.1)
				(type default)
			)
			(layer "F.Fab")
		)
		(fp_line
			(start -0.12065 0.2794)
			(end -0.12065 0.3048)
			(stroke
				(width 0.1)
				(type default)
			)
			(layer "F.Fab")
		)
		(fp_line
			(start 0.67945 0.3048)
			(end 0.120396 0.3048)
			(stroke
				(width 0.1)
				(type default)
			)
			(layer "F.Fab")
		)
		(fp_line
			(start 0.120396 0.3048)
			(end 0.120396 0.2794)
			(stroke
				(width 0.1)
				(type default)
			)
			(layer "F.Fab")
		)
		(fp_line
			(start -0.12065 0.3048)
			(end -0.67945 0.3048)
			(stroke
				(width 0.1)
				(type default)
			)
			(layer "F.Fab")
		)
		(fp_line
			(start -0.67945 0.3048)
			(end -0.67945 -0.305054)
			(stroke
				(width 0.1)
				(type default)
			)
			(layer "F.Fab")
		)
		(pad "1" smd circle
			(at -0.40005 0 90)
			(size 0 0)
			(layers "F.Cu" "F.Mask" "F.Paste")
			(net "P3V3_AUX")
		)
		(pad "2" smd circle
			(at 0.40005 0 90)
			(size 0 0)
			(layers "F.Cu" "F.Mask" "F.Paste")
			(net "U272_2_ADD1")
		)
	)
	(footprint ""
		(layer "F.Cu")
		(at 303.9872 -24.7396 180)
		(property "Reference" "C2386"
			(at 0 0 180)
			(layer "F.SilkS")
			(hide yes)
			(effects
				(font
					(size 1.27 1.27)
				)
			)
		)
		(property "Value" ""
			(at 0 0 180)
			(layer "F.Fab")
			(effects
				(font
					(size 1.27 1.27)
				)
			)
		)
		(duplicate_pad_numbers_are_jumpers no)
		(fp_line
			(start 0.7874 0.4064)
			(end -0.7874 0.4064)
			(stroke
				(width 0.1524)
				(type default)
			)
			(layer "F.SilkS")
		)
		(fp_line
			(start 0.7874 -0.4064)
			(end 0.7874 0.4064)
			(stroke
				(width 0.1524)
				(type default)
			)
			(layer "F.SilkS")
		)
		(fp_line
			(start -0.7874 0.4064)
			(end -0.7874 -0.4064)
			(stroke
				(width 0.1524)
				(type default)
			)
			(layer "F.SilkS")
		)
		(fp_line
			(start -0.7874 -0.4064)
			(end 0.7874 -0.4064)
			(stroke
				(width 0.1524)
				(type default)
			)
			(layer "F.SilkS")
		)
		(fp_line
			(start 0.67945 0.3048)
			(end 0.120396 0.3048)
			(stroke
				(width 0.1)
				(type default)
			)
			(layer "F.Fab")
		)
		(fp_line
			(start 0.67945 -0.3048)
			(end 0.67945 0.3048)
			(stroke
				(width 0.1)
				(type default)
			)
			(layer "F.Fab")
		)
		(fp_line
			(start 0.12065 -0.2794)
			(end 0.12065 -0.3048)
			(stroke
				(width 0.1)
				(type default)
			)
			(layer "F.Fab")
		)
		(fp_line
			(start 0.12065 -0.3048)
			(end 0.67945 -0.3048)
			(stroke
				(width 0.1)
				(type default)
			)
			(layer "F.Fab")
		)
		(fp_line
			(start 0.120396 0.3048)
			(end 0.120396 0.2794)
			(stroke
				(width 0.1)
				(type default)
			)
			(layer "F.Fab")
		)
		(fp_line
			(start 0.120396 0.2794)
			(end -0.12065 0.2794)
			(stroke
				(width 0.1)
				(type default)
			)
			(layer "F.Fab")
		)
		(fp_line
			(start -0.12065 0.3048)
			(end -0.67945 0.3048)
			(stroke
				(width 0.1)
				(type default)
			)
			(layer "F.Fab")
		)
		(fp_line
			(start -0.12065 0.2794)
			(end -0.12065 0.3048)
			(stroke
				(width 0.1)
				(type default)
			)
			(layer "F.Fab")
		)
		(fp_line
			(start -0.12065 -0.2794)
			(end 0.12065 -0.2794)
			(stroke
				(width 0.1)
				(type default)
			)
			(layer "F.Fab")
		)
		(fp_line
			(start -0.12065 -0.305054)
			(end -0.12065 -0.2794)
			(stroke
				(width 0.1)
				(type default)
			)
			(layer "F.Fab")
		)
		(fp_line
			(start -0.67945 0.3048)
			(end -0.67945 -0.305054)
			(stroke
				(width 0.1)
				(type default)
			)
			(layer "F.Fab")
		)
		(fp_line
			(start -0.67945 -0.305054)
			(end -0.12065 -0.305054)
			(stroke
				(width 0.1)
				(type default)
			)
			(layer "F.Fab")
		)
		(pad "1" smd circle
			(at -0.40005 0 180)
			(size 0 0)
			(layers "F.Cu" "F.Mask" "F.Paste")
			(net "PWRGD_DSW_PWROK_TRIGGER")
		)
		(pad "2" smd circle
			(at 0.40005 0 180)
			(size 0 0)
			(layers "F.Cu" "F.Mask" "F.Paste")
			(net "GND")
		)
	)
)
